# T6G (Grand Teton) — schematic netlist excerpt (pin names and nets, part order shuffled) for the footprints in the layout excerpt that follows; sources: Cadence DE-HDL packaged netlist, KiCad conversion of 04192023_DAF0TMB3IC0_F0TG_MB_C_brd_V02_OCP.brd

C6112  Q_CAP  1PF 50V 0.05P COG  pkg C0402  page 179 : A = P1V2_CPU0_USB2_DVDD12 ; B = GND
R809  Q_RES  0 5% CHIP  pkg 0201LF  page 185 : A = SMB_RT_CPU1_P2_ROM_MUX_2D_SCL ; B = SMB_RT_CPU1_P2_ROM_MUX_2D_R_SCL
R1226  Q_RES  9.09K 1% CHIP  pkg 0402LF  page 258 : A = P5V_AUX_ADC ; B = GND

(kicad_pcb
	(version 20260206)
	(generator "pcbnew")
	(generator_version "10.0")
	(general
		(thickness 1.6)
		(legacy_teardrops no)
	)
	(paper "A4")
	(title_block
		(title "04192023_DAF0TMB3IC0_F0TG_MB_C_brd_V02_OCP.brd")
		(comment 1 "Grand Teton / footprints 5371-5373 of 8354")
	)
	(layers
		(0 "F.Cu" signal "TOP")
		(4 "In1.Cu" signal "GND")
		(6 "In2.Cu" signal "IN1")
		(8 "In3.Cu" signal "GND1")
		(10 "In4.Cu" signal "IN2")
		(12 "In5.Cu" signal "GND2")
		(14 "In6.Cu" signal "IN3")
		(16 "In7.Cu" signal "GND3")
		(18 "In8.Cu" signal "VCC")
		(20 "In9.Cu" signal "VCC1")
		(22 "In10.Cu" signal "GND4")
		(24 "In11.Cu" signal "IN4")
		(26 "In12.Cu" signal "GND5")
		(28 "In13.Cu" signal "IN5")
		(30 "In14.Cu" signal "GND6")
		(32 "In15.Cu" signal "IN6")
		(34 "In16.Cu" signal "GND7")
		(2 "B.Cu" signal "BOTTOM")
		(9 "F.Adhes" user "F.Adhesive")
		(11 "B.Adhes" user "B.Adhesive")
		(13 "F.Paste" user "Package Geometry/Pastemask Top")
		(15 "B.Paste" user "Package Geometry/Pastemask Bottom")
		(5 "F.SilkS" user "Ref Des/Silkscreen Top")
		(7 "B.SilkS" user "Ref Des/Silkscreen Bottom")
		(1 "F.Mask" user "Board Geometry/Soldermask Top")
		(3 "B.Mask" user "Board Geometry/Soldermask Bottom")
		(17 "Dwgs.User" user "User.Drawings")
		(19 "Cmts.User" user "User.Comments")
		(21 "Eco1.User" user "User.Eco1")
		(23 "Eco2.User" user "User.Eco2")
		(25 "Edge.Cuts" user "Board Geometry/Outline")
		(27 "Margin" user)
		(31 "F.CrtYd" user "Package Geometry/Place Bound Top")
		(29 "B.CrtYd" user "Package Geometry/Place Bound Bottom")
		(35 "F.Fab" user "Ref Des/Assembly Top")
		(33 "B.Fab" user "Ref Des/Assembly Bottom")
	)
	(footprint ""
		(layer "B.Cu")
		(at 238.633 -341.884 180)
		(property "Reference" "R809"
			(at 0 0 0)
			(layer "B.SilkS")
			(hide yes)
			(effects
				(font
					(size 1.27 1.27)
				)
				(justify mirror)
			)
		)
		(property "Value" ""
			(at 0 0 0)
			(layer "B.Fab")
			(effects
				(font
					(size 1.27 1.27)
				)
				(justify mirror)
			)
		)
		(duplicate_pad_numbers_are_jumpers no)
		(fp_line
			(start 0.32512 0.175006)
			(end 0.32512 -0.175006)
			(stroke
				(width 0.1)
				(type default)
			)
			(layer "B.Fab")
		)
		(fp_line
			(start 0.32512 -0.175006)
			(end -0.32512 -0.175006)
			(stroke
				(width 0.1)
				(type default)
			)
			(layer "B.Fab")
		)
		(fp_line
			(start -0.32512 0.175006)
			(end 0.32512 0.175006)
			(stroke
				(width 0.1)
				(type default)
			)
			(layer "B.Fab")
		)
		(fp_line
			(start -0.32512 -0.175006)
			(end -0.32512 0.175006)
			(stroke
				(width 0.1)
				(type default)
			)
			(layer "B.Fab")
		)
		(pad "1" smd rect
			(at 0.2667 0)
			(size 0.3048 0.381)
			(layers "B.Cu" "B.Mask" "B.Paste")
			(net "SMB_RT_CPU1_P2_ROM_MUX_2D_SCL")
		)
		(pad "2" smd rect
			(at -0.2667 0 180)
			(size 0.3048 0.381)
			(layers "B.Cu" "B.Mask" "B.Paste")
			(net "SMB_RT_CPU1_P2_ROM_MUX_2D_R_SCL")
		)
	)
	(footprint ""
		(layer "B.Cu")
		(at 106.869992 -31.33344 90)
		(property "Reference" "C6112"
			(at 0 0 90)
			(layer "B.SilkS")
			(hide yes)
			(effects
				(font
					(size 1.27 1.27)
				)
				(justify mirror)
			)
		)
		(property "Value" ""
			(at 0 0 90)
			(layer "B.Fab")
			(effects
				(font
					(size 1.27 1.27)
				)
				(justify mirror)
			)
		)
		(duplicate_pad_numbers_are_jumpers no)
		(fp_line
			(start 0.7874 -0.4064)
			(end -0.7874 -0.4064)
			(stroke
				(width 0.1524)
				(type default)
			)
			(layer "B.SilkS")
		)
		(fp_line
			(start -0.7874 -0.4064)
			(end -0.7874 0.4064)
			(stroke
				(width 0.1524)
				(type default)
			)
			(layer "B.SilkS")
		)
		(fp_line
			(start 0.7874 0.4064)
			(end 0.7874 -0.4064)
			(stroke
				(width 0.1524)
				(type default)
			)
			(layer "B.SilkS")
		)
		(fp_line
			(start -0.7874 0.4064)
			(end 0.7874 0.4064)
			(stroke
				(width 0.1524)
				(type default)
			)
			(layer "B.SilkS")
		)
		(fp_line
			(start 0.67945 -0.305054)
			(end 0.12065 -0.305054)
			(stroke
				(width 0.1)
				(type default)
			)
			(layer "B.Fab")
		)
		(fp_line
			(start 0.12065 -0.305054)
			(end 0.12065 -0.2794)
			(stroke
				(width 0.1)
				(type default)
			)
			(layer "B.Fab")
		)
		(fp_line
			(start -0.12065 -0.3048)
			(end -0.67945 -0.3048)
			(stroke
				(width 0.1)
				(type default)
			)
			(layer "B.Fab")
		)
		(fp_line
			(start -0.67945 -0.3048)
			(end -0.67945 0.3048)
			(stroke
				(width 0.1)
				(type default)
			)
			(layer "B.Fab")
		)
		(fp_line
			(start 0.12065 -0.2794)
			(end -0.12065 -0.2794)
			(stroke
				(width 0.1)
				(type default)
			)
			(layer "B.Fab")
		)
		(fp_line
			(start -0.12065 -0.2794)
			(end -0.12065 -0.3048)
			(stroke
				(width 0.1)
				(type default)
			)
			(layer "B.Fab")
		)
		(fp_line
			(start 0.12065 0.2794)
			(end 0.12065 0.3048)
			(stroke
				(width 0.1)
				(type default)
			)
			(layer "B.Fab")
		)
		(fp_line
			(start -0.120396 0.2794)
			(end 0.12065 0.2794)
			(stroke
				(width 0.1)
				(type default)
			)
			(layer "B.Fab")
		)
		(fp_line
			(start 0.67945 0.3048)
			(end 0.67945 -0.305054)
			(stroke
				(width 0.1)
				(type default)
			)
			(layer "B.Fab")
		)
		(fp_line
			(start 0.12065 0.3048)
			(end 0.67945 0.3048)
			(stroke
				(width 0.1)
				(type default)
			)
			(layer "B.Fab")
		)
		(fp_line
			(start -0.120396 0.3048)
			(end -0.120396 0.2794)
			(stroke
				(width 0.1)
				(type default)
			)
			(layer "B.Fab")
		)
		(fp_line
			(start -0.67945 0.3048)
			(end -0.120396 0.3048)
			(stroke
				(width 0.1)
				(type default)
			)
			(layer "B.Fab")
		)
		(pad "1" smd circle
			(at 0.40005 0 270)
			(size 0 0)
			(layers "B.Cu" "B.Mask" "B.Paste")
			(net "P1V2_CPU0_USB2_DVDD12")
		)
		(pad "2" smd circle
			(at -0.40005 0 270)
			(size 0 0)
			(layers "B.Cu" "B.Mask" "B.Paste")
			(net "GND")
		)
	)
	(footprint ""
		(layer "B.Cu")
		(at 234.785916 -321.652138 180)
		(property "Reference" "R1226"
			(at 0 0 0)
			(layer "B.SilkS")
			(hide yes)
			(effects
				(font
					(size 1.27 1.27)
				)
				(justify mirror)
			)
		)
		(property "Value" ""
			(at 0 0 0)
			(layer "B.Fab")
			(effects
				(font
					(size 1.27 1.27)
				)
				(justify mirror)
			)
		)
		(duplicate_pad_numbers_are_jumpers no)
		(fp_line
			(start 0.7874 0.4064)
			(end 0.7874 -0.4064)
			(stroke
				(width 0.1524)
				(type default)
			)
			(layer "B.SilkS")
		)
		(fp_line
			(start 0.7874 -0.4064)
			(end -0.7874 -0.4064)
			(stroke
				(width 0.1524)
				(type default)
			)
			(layer "B.SilkS")
		)
		(fp_line
			(start -0.7874 0.4064)
			(end 0.7874 0.4064)
			(stroke
				(width 0.1524)
				(type default)
			)
			(layer "B.SilkS")
		)
		(fp_line
			(start -0.7874 -0.4064)
			(end -0.7874 0.4064)
			(stroke
				(width 0.1524)
				(type default)
			)
			(layer "B.SilkS")
		)
		(fp_line
			(start 0.67945 0.3048)
			(end 0.67945 -0.305054)
			(stroke
				(width 0.1)
				(type default)
			)
			(layer "B.Fab")
		)
		(fp_line
			(start 0.67945 -0.305054)
			(end 0.12065 -0.305054)
			(stroke
				(width 0.1)
				(type default)
			)
			(layer "B.Fab")
		)
		(fp_line
			(start 0.12065 0.3048)
			(end 0.67945 0.3048)
			(stroke
				(width 0.1)
				(type default)
			)
			(layer "B.Fab")
		)
		(fp_line
			(start 0.12065 0.2794)
			(end 0.12065 0.3048)
			(stroke
				(width 0.1)
				(type default)
			)
			(layer "B.Fab")
		)
		(fp_line
			(start 0.12065 -0.2794)
			(end -0.12065 -0.2794)
			(stroke
				(width 0.1)
				(type default)
			)
			(layer "B.Fab")
		)
		(fp_line
			(start 0.12065 -0.305054)
			(end 0.12065 -0.2794)
			(stroke
				(width 0.1)
				(type default)
			)
			(layer "B.Fab")
		)
		(fp_line
			(start -0.120396 0.3048)
			(end -0.120396 0.2794)
			(stroke
				(width 0.1)
				(type default)
			)
			(layer "B.Fab")
		)
		(fp_line
			(start -0.120396 0.2794)
			(end 0.12065 0.2794)
			(stroke
				(width 0.1)
				(type default)
			)
			(layer "B.Fab")
		)
		(fp_line
			(start -0.12065 -0.2794)
			(end -0.12065 -0.3048)
			(stroke
				(width 0.1)
				(type default)
			)
			(layer "B.Fab")
		)
		(fp_line
			(start -0.12065 -0.3048)
			(end -0.67945 -0.3048)
			(stroke
				(width 0.1)
				(type default)
			)
			(layer "B.Fab")
		)
		(fp_line
			(start -0.67945 0.3048)
			(end -0.120396 0.3048)
			(stroke
				(width 0.1)
				(type default)
			)
			(layer "B.Fab")
		)
		(fp_line
			(start -0.67945 -0.3048)
			(end -0.67945 0.3048)
			(stroke
				(width 0.1)
				(type default)
			)
			(layer "B.Fab")
		)
		(pad "1" smd circle
			(at 0.40005 0)
			(size 0 0)
			(layers "B.Cu" "B.Mask" "B.Paste")
			(net "P5V_AUX_ADC")
		)
		(pad "2" smd circle
			(at -0.40005 0)
			(size 0 0)
			(layers "B.Cu" "B.Mask" "B.Paste")
			(net "GND")
		)
	)
)
